# S9S_MB_2U (Grand Teton) — schematic netlist excerpt (pin names and nets, part order shuffled) for the footprints in the layout excerpt that follows; sources: Cadence DE-HDL packaged netlist, KiCad conversion of 03242023_DA0F0TMBIJ0_F0T_Motherboard_J_brd_V01_OCP.brd

C58  Q_CAP  10UF 16V 10% X6S  pkg C0805  page 100 : A = P12V_S3_AUX_CPU1_NVDIMM ; B = GND
R2811  Q_RES  33.2 1% CHIP  pkg 0402LF  page 245 : A = SMB_FAN_3V3AUX_BUF_SCL ; B = SMB_FAN_3V3AUX_BUF_R_SCL
R1896  Q_RES  100 1% CHIP  pkg 0402LF  page 154 : A = OCP_SFF_ISO_BIF0_EN ; B = GND

(kicad_pcb
	(version 20260206)
	(generator "pcbnew")
	(generator_version "10.0")
	(general
		(thickness 1.6)
		(legacy_teardrops no)
	)
	(paper "A4")
	(title_block
		(title "03242023_DA0F0TMBIJ0_F0T_Motherboard_J_brd_V01_OCP.brd")
		(comment 1 "Grand Teton / footprints 5305-5307 of 6105")
	)
	(layers
		(0 "F.Cu" signal "TOP")
		(4 "In1.Cu" signal "GND")
		(6 "In2.Cu" signal "IN1")
		(8 "In3.Cu" signal "GND1")
		(10 "In4.Cu" signal "IN2")
		(12 "In5.Cu" signal "GND2")
		(14 "In6.Cu" signal "IN3")
		(16 "In7.Cu" signal "GND3")
		(18 "In8.Cu" signal "VCC")
		(20 "In9.Cu" signal "VCC1")
		(22 "In10.Cu" signal "GND4")
		(24 "In11.Cu" signal "IN4")
		(26 "In12.Cu" signal "GND5")
		(28 "In13.Cu" signal "IN5")
		(30 "In14.Cu" signal "GND6")
		(32 "In15.Cu" signal "IN6")
		(34 "In16.Cu" signal "GND7")
		(2 "B.Cu" signal "BOTTOM")
		(9 "F.Adhes" user "F.Adhesive")
		(11 "B.Adhes" user "B.Adhesive")
		(13 "F.Paste" user "Package Geometry/Pastemask Top")
		(15 "B.Paste" user "Package Geometry/Pastemask Bottom")
		(5 "F.SilkS" user "Ref Des/Silkscreen Top")
		(7 "B.SilkS" user "Ref Des/Silkscreen Bottom")
		(1 "F.Mask" user "Board Geometry/Soldermask Top")
		(3 "B.Mask" user "Board Geometry/Soldermask Bottom")
		(17 "Dwgs.User" user "User.Drawings")
		(19 "Cmts.User" user "User.Comments")
		(21 "Eco1.User" user "User.Eco1")
		(23 "Eco2.User" user "User.Eco2")
		(25 "Edge.Cuts" user "Board Geometry/Outline")
		(27 "Margin" user)
		(31 "F.CrtYd" user "Package Geometry/Place Bound Top")
		(29 "B.CrtYd" user "Package Geometry/Place Bound Bottom")
		(35 "F.Fab" user "Ref Des/Assembly Top")
		(33 "B.Fab" user "Ref Des/Assembly Bottom")
	)
	(footprint ""
		(layer "B.Cu")
		(at 179.091082 -422.273222 90)
		(property "Reference" "R2811"
			(at 0 0 90)
			(layer "B.SilkS")
			(hide yes)
			(effects
				(font
					(size 1.27 1.27)
				)
				(justify mirror)
			)
		)
		(property "Value" ""
			(at 0 0 90)
			(layer "B.Fab")
			(effects
				(font
					(size 1.27 1.27)
				)
				(justify mirror)
			)
		)
		(duplicate_pad_numbers_are_jumpers no)
		(fp_line
			(start 0.7874 -0.4064)
			(end -0.7874 -0.4064)
			(stroke
				(width 0.1524)
				(type default)
			)
			(layer "B.SilkS")
		)
		(fp_line
			(start -0.7874 -0.4064)
			(end -0.7874 0.4064)
			(stroke
				(width 0.1524)
				(type default)
			)
			(layer "B.SilkS")
		)
		(fp_line
			(start 0.7874 0.4064)
			(end 0.7874 -0.4064)
			(stroke
				(width 0.1524)
				(type default)
			)
			(layer "B.SilkS")
		)
		(fp_line
			(start -0.7874 0.4064)
			(end 0.7874 0.4064)
			(stroke
				(width 0.1524)
				(type default)
			)
			(layer "B.SilkS")
		)
		(fp_line
			(start 0.67945 -0.305054)
			(end 0.12065 -0.305054)
			(stroke
				(width 0.1)
				(type default)
			)
			(layer "B.Fab")
		)
		(fp_line
			(start 0.12065 -0.305054)
			(end 0.12065 -0.2794)
			(stroke
				(width 0.1)
				(type default)
			)
			(layer "B.Fab")
		)
		(fp_line
			(start -0.12065 -0.3048)
			(end -0.67945 -0.3048)
			(stroke
				(width 0.1)
				(type default)
			)
			(layer "B.Fab")
		)
		(fp_line
			(start -0.67945 -0.3048)
			(end -0.67945 0.3048)
			(stroke
				(width 0.1)
				(type default)
			)
			(layer "B.Fab")
		)
		(fp_line
			(start 0.12065 -0.2794)
			(end -0.12065 -0.2794)
			(stroke
				(width 0.1)
				(type default)
			)
			(layer "B.Fab")
		)
		(fp_line
			(start -0.12065 -0.2794)
			(end -0.12065 -0.3048)
			(stroke
				(width 0.1)
				(type default)
			)
			(layer "B.Fab")
		)
		(fp_line
			(start 0.12065 0.2794)
			(end 0.12065 0.3048)
			(stroke
				(width 0.1)
				(type default)
			)
			(layer "B.Fab")
		)
		(fp_line
			(start -0.120396 0.2794)
			(end 0.12065 0.2794)
			(stroke
				(width 0.1)
				(type default)
			)
			(layer "B.Fab")
		)
		(fp_line
			(start 0.67945 0.3048)
			(end 0.67945 -0.305054)
			(stroke
				(width 0.1)
				(type default)
			)
			(layer "B.Fab")
		)
		(fp_line
			(start 0.12065 0.3048)
			(end 0.67945 0.3048)
			(stroke
				(width 0.1)
				(type default)
			)
			(layer "B.Fab")
		)
		(fp_line
			(start -0.120396 0.3048)
			(end -0.120396 0.2794)
			(stroke
				(width 0.1)
				(type default)
			)
			(layer "B.Fab")
		)
		(fp_line
			(start -0.67945 0.3048)
			(end -0.120396 0.3048)
			(stroke
				(width 0.1)
				(type default)
			)
			(layer "B.Fab")
		)
		(pad "1" smd circle
			(at 0.40005 0 270)
			(size 0 0)
			(layers "B.Cu" "B.Mask" "B.Paste")
			(net "SMB_FAN_3V3AUX_BUF_SCL")
		)
		(pad "2" smd circle
			(at -0.40005 0 270)
			(size 0 0)
			(layers "B.Cu" "B.Mask" "B.Paste")
			(net "SMB_FAN_3V3AUX_BUF_R_SCL")
		)
	)
	(footprint ""
		(layer "B.Cu")
		(at 38.328346 -321.554856 -90)
		(property "Reference" "C58"
			(at 0 0 90)
			(layer "B.SilkS")
			(hide yes)
			(effects
				(font
					(size 1.27 1.27)
				)
				(justify mirror)
			)
		)
		(property "Value" ""
			(at 0 0 90)
			(layer "B.Fab")
			(effects
				(font
					(size 1.27 1.27)
				)
				(justify mirror)
			)
		)
		(duplicate_pad_numbers_are_jumpers no)
		(fp_line
			(start -1.524 0.762)
			(end 1.524 0.762)
			(stroke
				(width 0.1524)
				(type default)
			)
			(layer "B.SilkS")
		)
		(fp_line
			(start 1.524 0.762)
			(end 1.524 -0.762)
			(stroke
				(width 0.1524)
				(type default)
			)
			(layer "B.SilkS")
		)
		(fp_line
			(start -1.524 -0.762)
			(end -1.524 0.762)
			(stroke
				(width 0.1524)
				(type default)
			)
			(layer "B.SilkS")
		)
		(fp_line
			(start 1.524 -0.762)
			(end -1.524 -0.762)
			(stroke
				(width 0.1524)
				(type default)
			)
			(layer "B.SilkS")
		)
		(fp_line
			(start -1.1049 0.724916)
			(end -1.1049 -0.724916)
			(stroke
				(width 0.1)
				(type default)
			)
			(layer "B.Fab")
		)
		(fp_line
			(start 1.1049 0.724916)
			(end -1.1049 0.724916)
			(stroke
				(width 0.1)
				(type default)
			)
			(layer "B.Fab")
		)
		(fp_line
			(start -1.1049 -0.724916)
			(end 1.1049 -0.724916)
			(stroke
				(width 0.1)
				(type default)
			)
			(layer "B.Fab")
		)
		(fp_line
			(start 1.1049 -0.724916)
			(end 1.1049 0.724916)
			(stroke
				(width 0.1)
				(type default)
			)
			(layer "B.Fab")
		)
		(pad "1" smd rect
			(at 0.889 0 270)
			(size 1.016 1.27)
			(layers "B.Cu" "B.Mask" "B.Paste")
			(net "P12V_S3_AUX_CPU1_NVDIMM")
		)
		(pad "2" smd rect
			(at -0.889 0 270)
			(size 1.016 1.27)
			(layers "B.Cu" "B.Mask" "B.Paste")
			(net "GND")
		)
	)
	(footprint ""
		(layer "B.Cu")
		(at 432.562 -24.094948 -90)
		(property "Reference" "R1896"
			(at 0 0 90)
			(layer "B.SilkS")
			(hide yes)
			(effects
				(font
					(size 1.27 1.27)
				)
				(justify mirror)
			)
		)
		(property "Value" ""
			(at 0 0 90)
			(layer "B.Fab")
			(effects
				(font
					(size 1.27 1.27)
				)
				(justify mirror)
			)
		)
		(duplicate_pad_numbers_are_jumpers no)
		(fp_line
			(start -0.7874 0.4064)
			(end 0.7874 0.4064)
			(stroke
				(width 0.1524)
				(type default)
			)
			(layer "B.SilkS")
		)
		(fp_line
			(start 0.7874 0.4064)
			(end 0.7874 -0.4064)
			(stroke
				(width 0.1524)
				(type default)
			)
			(layer "B.SilkS")
		)
		(fp_line
			(start -0.7874 -0.4064)
			(end -0.7874 0.4064)
			(stroke
				(width 0.1524)
				(type default)
			)
			(layer "B.SilkS")
		)
		(fp_line
			(start 0.7874 -0.4064)
			(end -0.7874 -0.4064)
			(stroke
				(width 0.1524)
				(type default)
			)
			(layer "B.SilkS")
		)
		(fp_line
			(start -0.67945 0.3048)
			(end -0.120396 0.3048)
			(stroke
				(width 0.1)
				(type default)
			)
			(layer "B.Fab")
		)
		(fp_line
			(start -0.120396 0.3048)
			(end -0.120396 0.2794)
			(stroke
				(width 0.1)
				(type default)
			)
			(layer "B.Fab")
		)
		(fp_line
			(start 0.12065 0.3048)
			(end 0.67945 0.3048)
			(stroke
				(width 0.1)
				(type default)
			)
			(layer "B.Fab")
		)
		(fp_line
			(start 0.67945 0.3048)
			(end 0.67945 -0.305054)
			(stroke
				(width 0.1)
				(type default)
			)
			(layer "B.Fab")
		)
		(fp_line
			(start -0.120396 0.2794)
			(end 0.12065 0.2794)
			(stroke
				(width 0.1)
				(type default)
			)
			(layer "B.Fab")
		)
		(fp_line
			(start 0.12065 0.2794)
			(end 0.12065 0.3048)
			(stroke
				(width 0.1)
				(type default)
			)
			(layer "B.Fab")
		)
		(fp_line
			(start -0.12065 -0.2794)
			(end -0.12065 -0.3048)
			(stroke
				(width 0.1)
				(type default)
			)
			(layer "B.Fab")
		)
		(fp_line
			(start 0.12065 -0.2794)
			(end -0.12065 -0.2794)
			(stroke
				(width 0.1)
				(type default)
			)
			(layer "B.Fab")
		)
		(fp_line
			(start -0.67945 -0.3048)
			(end -0.67945 0.3048)
			(stroke
				(width 0.1)
				(type default)
			)
			(layer "B.Fab")
		)
		(fp_line
			(start -0.12065 -0.3048)
			(end -0.67945 -0.3048)
			(stroke
				(width 0.1)
				(type default)
			)
			(layer "B.Fab")
		)
		(fp_line
			(start 0.12065 -0.305054)
			(end 0.12065 -0.2794)
			(stroke
				(width 0.1)
				(type default)
			)
			(layer "B.Fab")
		)
		(fp_line
			(start 0.67945 -0.305054)
			(end 0.12065 -0.305054)
			(stroke
				(width 0.1)
				(type default)
			)
			(layer "B.Fab")
		)
		(pad "1" smd circle
			(at 0.40005 0 90)
			(size 0 0)
			(layers "B.Cu" "B.Mask" "B.Paste")
			(net "OCP_SFF_ISO_BIF0_EN")
		)
		(pad "2" smd circle
			(at -0.40005 0 90)
			(size 0 0)
			(layers "B.Cu" "B.Mask" "B.Paste")
			(net "GND")
		)
	)
)
